# BASEBOARD_FAB2 (Tioga Pass) — schematic parts with pin connectivity, parts 2833–2988 of 4751; source: Cadence DE-HDL packaged netlist (pstxprt.dat, pstxnet.dat, pstchip.dat)

R1W28  RES  0.0 5% CHIP  pkg 0402  page 191 : 1 = FM_PCH_PWRBTN_R1_N ; 2 = FM_PCH_PWRBTN_N
R1W29  RES  0.0 5% CHIP  pkg 0402  page 191 : 1 = RST_BMC_SYSRST_BTN_OUT_B_N ; 2 = RST_BMC_SYSRST_BTN_OUT_B_R1_N
R1W30  RES  0.0 5% EMPTY  pkg 0402  page 118 : 1 = RST_BMC_SYSRST_BTN_OUT_B_N ; 2 = RST_SYSTEM_BTN_BUF_N
R1W31  RES  330 5% CHIP  pkg 0402  page 89 : 1 = FM_ADR_COMPLETE_R ; 2 = FM_ADR_COMPLETE_CPU1_R
R1W32  RES  330 5% CHIP  pkg 0402  page 89 : 1 = FM_ADR_COMPLETE_R ; 2 = FM_ADR_COMPLETE_CPU0_R
R1W33  RES  0.0 5% CHIP  pkg 0402  page 176 : 1 = SMB_DEBUG_STBY_LVC3_SCL_R1 ; 2 = SMB_DEBUG_STBY_LVC3_SCL
R1W34  RES  0.0 5% CHIP  pkg 0402  page 176 : 1 = SMB_DEBUG_STBY_LVC3_SDA_R1 ; 2 = SMB_DEBUG_STBY_LVC3_SDA
R1W35  RES  49.9 1% EMPTY  pkg 0402  page 152 : 1 = PVCCIO_CPU0 ; 2 = P0V7_GTL2014_2
R1W36  RES  4.75K 1% CHIP  pkg 0402  page 176 : 1 = P3V3_STBY ; 2 = SMB_DEBUG_STBY_LVC3_SCL_CONN
R1W37  RES  4.75K 1% CHIP  pkg 0402  page 176 : 1 = P3V3_STBY ; 2 = SMB_DEBUG_STBY_LVC3_SDA_CONN
R1W38  RES  0.0 5% CHIP  pkg 0402  page 176 : 1 = SMB_DEBUG_STBY_LVC3_SCL_CONN ; 2 = SMB_DEBUG_STBY_LVC3_SCL_R1
R1W39  RES  0.0 5% CHIP  pkg 0402  page 176 : 1 = SMB_DEBUG_STBY_LVC3_SDA_CONN ; 2 = SMB_DEBUG_STBY_LVC3_SDA_R1
R1W40  RES  4.75K 1% CHIP  pkg 0402  page 188 : 1 = P3V3_STBY ; 2 = EXT_MDIO_I2C_SEL
R1W41  RES  4.75K 1% CHIP  pkg 0402  page 188 : 1 = GND ; 2 = EXT_MDIO_I2C_SEL
R1W42  RES  4.75K 1% CHIP  pkg 0402  page 188 : 1 = P3V3_STBY ; 2 = FM_GBE0_LVC3_MOD_ABS
R1W43  RES  4.75K 1% CHIP  pkg 0402  page 188 : 1 = P3V3_STBY ; 2 = FM_GBE1_LVC3_MOD_ABS
R1W44  RES  4.75K 1% CHIP  pkg 0402  page 188 : 1 = P3V3_STBY ; 2 = FM_GBE2_LVC3_MOD_ABS
R1W45  RES  4.75K 1% CHIP  pkg 0402  page 188 : 1 = P3V3_STBY ; 2 = FM_GBE3_LVC3_MOD_ABS
R2L4  RES  2.0K 1% CHIP  pkg 0402  page 178 : 1 = P3V3_STBY ; 2 = SGPIO_PCH_SSATA_DOUT0_R
R2L5  RES  2.0K 1% CHIP  pkg 0402  page 178 : 1 = P3V3_STBY ; 2 = SGPIO_PCH_SSATA_LOAD_R
R2L6  RES  2.0K 1% CHIP  pkg 0402  page 178 : 1 = P3V3_STBY ; 2 = SGPIO_PCH_SSATA_CLOCK_R
R2L8  RES  10.0 1% CHIP  pkg 0603  page 235 : 1 = VSENSE_P1V05_PCH_STBY_AVSP ; 2 = VR_P1V05_PCH_STBY_AVSP
R2L9  RES  4.02K 1% CHIP  pkg 0402  page 235 : 1 = VR_PVNN_PCH_XADDR1 ; 2 = GND
R2L10  RES  1.5K 1% CHIP  pkg 0402  page 235 : 1 = VR_PVNN_PCH_VINSEN ; 2 = GND
R2L11  RES  2.0K 1% CHIP  pkg 0402  page 178 : 1 = P3V3_STBY ; 2 = SGPIO_PCH_SATA_CLOCK_R
R2L12  RES  2.0K 1% CHIP  pkg 0402  page 178 : 1 = P3V3_STBY ; 2 = SGPIO_PCH_SATA_LOAD_R
R2L14  RES  0.0 5% CHIP  pkg 0402  page 235 : 1 = P3V3_STBY ; 2 = VR_PVNN_PCH_VDD
R2L15  RES  2.0K 1% CHIP  pkg 0402  page 178 : 1 = P3V3_STBY ; 2 = SGPIO_PCH_SATA_DOUT0_R
R2L16  RES  22.1 1.0% CHIP  pkg 0402  page 235 : 1 = PWRGD_PVNN_PCH_R ; 2 = PWRGD_PVNN_P1V05_PCH
R2L17  RES  0.0 5% CHIP  pkg 0402  page 235 : 1 = PWRGD_P1V8_PCH_STBY ; 2 = VR_PVNN_PCH_VREN
R2L18  RES  1.00K 1% CHIP  pkg 0402  page 173 : 1 = PD_SATA0_CONTROLLER_TYPE_R ; 2 = GND
R2L19  RES  49.9K 1% CHIP  pkg 0402  page 237 : 1 = VR_P1V8_PCH_STBY_FB ; 2 = GND
R2L20  RES  63.4K 1.0% CHIP  pkg 0402  page 237 : 1 = P1V8_PCH_STBY ; 2 = VR_P1V8_PCH_STBY_FB
R2L21  RES  2.0K 1% CHIP  pkg 0402  page 173 : 1 = P3V3 ; 2 = PU_DATAIN1_SATA_0_R
R2L22  RES  1.00K 1% CHIP  pkg 0402  page 173 : 1 = PD_SATA1_CONTROLLER_TYPE_R ; 2 = GND
R2L23  RES  2.0K 1% CHIP  pkg 0402  page 173 : 1 = P3V3 ; 2 = PU_DATAIN1_SATA_1_R
R2L24  RES  2.26K 1.0% EMPTY  pkg 0402  page 235 : 1 = P3V3_STBY ; 2 = PU_VR_PVNN_PCH_FAULT1
R2L25  RES  100.0K 1% CHIP  pkg 0402  page 235 : 1 = P3V3_STBY ; 2 = VID_PCH_CORE_PVNN_AUX_VID_1
R2L26  RES  100.0K 1% CHIP  pkg 0402  page 235 : 1 = P3V3_STBY ; 2 = VID_PCH_CORE_PVNN_AUX_VID_0
R2M1  RES  33.2 1% CHIP  pkg 0402  page 120 : 1 = FM_CPLD_ADR_TRIGGER_N ; 2 = FM_CPLD_ADR_TRIGGER_R_N
R2M2  RES  4.75K 1% CHIP  pkg 0402  page 157 : 1 = P3V3_STBY ; 2 = FM_ADR_SMI_GPIO_N
R2M3  RES  33.2 1% CHIP  pkg 0402  page 119 : 1 = FM_PCH_PLD_DATA_R ; 2 = FM_PCH_PLD_DATA
R2M4  RES  1.00K 1% CHIP  pkg 0402  page 133 : 1 = P3V3_STBY ; 2 = IRQ_HSC_FAULT_N
R2M5  RES  4.75K 1% CHIP  pkg 0402  page 157 : 1 = P3V3_STBY ; 2 = FM_BMC_CPLD_GPO
R2M6  RES  1.0K 0.1% CHIP  pkg 0402  page 118 : 1 = A_KR1_RBIAS ; 2 = P1V05_PCH_STBY_KR_PLL
R2M7  RES  33.2 1% CHIP  pkg 0402  page 119 : 1 = FM_ADR_MODE_SEL_R ; 2 = FM_ADR_MODE_SEL
R2M8  RES  1.5K 1% CHIP  pkg 0402  page 133 : 1 = P3V3_STBY ; 2 = FM_CPU0_RC_ERROR_N
R2N1  RES  33.2 1% CHIP  pkg 0402  page 119 : 1 = FM_CPU_CATERR_DLY_LVT3_R_N ; 2 = FM_CPU_CATERR_DLY_LVT3_N
R2N4  RES  1.0K 0.1% CHIP  pkg 0402  page 118 : 1 = P1V05_PCH_STBY_KR_PLL ; 2 = A_KR0_RBIAS
R2N5  RES  665 1.0% CHIP  pkg 0402  page 138 : 1 = P3V3_STBY ; 2 = SMB_SMLINK0_STBY_LVC3_SCL
R2N6  RES  10.0K 1% CHIP  pkg 0402  page 118 : 1 = P3V3_STBY ; 2 = FM_GBE_LOM_DISABLE_N
R2N7  RES  4.75K 1% CHIP  pkg 0402  page 133 : 1 = P3V3_STBY ; 2 = IRQ_BOARD_BMC_ALERT_N
R2N8  RES  665 1.0% CHIP  pkg 0402  page 138 : 1 = P3V3_STBY ; 2 = SMB_SMLINK0_STBY_LVC3_SDA
R2N9  RES  10.0K 1% CHIP  pkg 0402  page 133 : 1 = P3V3_STBY ; 2 = PU_10GBE_LOM_PCI_DISABLE_N
R2N10  RES  4.75K 1% EMPTY  pkg 0402  page 126 : 1 = P3V3_STBY ; 2 = FM_PCH_BMC_THERMTRIP_EXI_STRAP_
R2N12  RES  10.0K 1% EMPTY  pkg 0402  page 133 : 1 = GND ; 2 = PWRGD_SYS_PWROK
R2N13  RES  10.0K 1% CHIP  pkg 0402  page 147 : 1 = FM_BIOS_PREFRB2_GOOD ; 2 = GND
R2N14  RES  1.00K 1% EMPTY  pkg 0402  page 125 : 1 = P3V3_STBY ; 2 = FM_USB_P0_EN_BOOT_BIOS_STRAP_N
R2N16  RES  10.0K 1% CHIP  pkg 0402  page 133 : 1 = P3V3_STBY ; 2 = PU_IRQ_VRALERT_N
R2N17  RES  2.7K 1% CHIP  pkg 0402  page 164 : 1 = P3V3_STBY ; 2 = FM_BOARD_SKU_ID4
R2N18  RES  1.00K 1% CHIP  pkg 0402  page 164 : 1 = FM_BOARD_SKU_ID4 ; 2 = GND
R2N19  RES  49.9 1% CHIP  pkg 0402  page 178 : 1 = SGPIO_PCH_SSATA_LOAD ; 2 = SGPIO_PCH_SSATA_LOAD_R
R2N20  RES  0.0 5% CHIP  pkg 0402  page 138 : 1 = SMB_LAN_STBY_LVC3_SDA_R2 ; 2 = SMB_LAN_STBY_LVC3_SDA
R2N21  RES  0.0 5% CHIP  pkg 0402  page 138 : 1 = SMB_LAN_STBY_LVC3_SCL_R2 ; 2 = SMB_LAN_STBY_LVC3_SCL
R2N22  RES  49.9 1% CHIP  pkg 0402  page 178 : 1 = SGPIO_PCH_SSATA_CLOCK ; 2 = SGPIO_PCH_SSATA_CLOCK_R
R2N23  RES  10.0K 1% CHIP  pkg 0402  page 135 : 1 = P3V3_STBY ; 2 = FM_QAT_EN_N
R2N24  RES  1.00K 1% EMPTY  pkg 0402  page 135 : 1 = FM_QAT_EN_N ; 2 = GND
R2N25  RES  51.1 1.0% CHIP  pkg 0402  page 157 : 1 = FM_NMI_EVENT_N ; 2 = FM_BMC_NMI_N
R2N26  RES  33.2 1% CHIP  pkg 0402  page 120 : 1 = FM_ADR_COMPLETE ; 2 = FM_ADR_COMPLETE_R1
R2N27  RES  4.75K 1% CHIP  pkg 0402  page 157 : 1 = P3V3 ; 2 = FM_BMC_NMI_N
R2N28  RES  10.0K 1% CHIP  pkg 0402  page 136 : 1 = P3V3_STBY ; 2 = FM_PASSWORD_CLEAR_N
R2N29  RES  1.5K 1% CHIP  pkg 0402  page 133 : 1 = P3V3_STBY ; 2 = FM_CPU1_RC_ERROR_N
R2N31  RES  49.9 1% CHIP  pkg 0402  page 178 : 1 = SGPIO_PCH_SATA_CLOCK ; 2 = SGPIO_PCH_SATA_CLOCK_R
R2N32  RES  4.75K 1% CHIP  pkg 0402  page 133 : 1 = P3V3_STBY ; 2 = FM_BIOS_SMI_ACTIVE_N
R2P1  RES  0.0 5% CHIP  pkg 0402  page 121 : 1 = RMII_SPRNGVLLE_BMC_PCH_RXD1 ; 2 = RMII_SPRNGVLLE_BMC_PCH_RXD1_R1
R2P2  RES  1.00K 1% CHIP  pkg 0402  page 111 : 1 = SPI_PCH_IO2 ; 2 = XDP_DEBUG_CONSENT_N
R2P3  RES  4.75K 1% CHIP  pkg 0402  page 170 : 1 = P3V3_STBY ; 2 = IRQ_FORCE_NM_THROTTLE_R_N
R2P4  RES  33.2 1% CHIP  pkg 0402  page 170 : 1 = IRQ_FORCE_NM_THROTTLE_R_N ; 2 = IRQ_FORCE_NM_THROTTLE_N
R2P5  RES  4.75K 1% CHIP  pkg 0402  page 170 : 1 = P3V3_STBY ; 2 = FM_PMBUS_ALERT_BUF_EN
R2P8  RES  4.75K 1% CHIP  pkg 0402  page 170 : 1 = P3V3_STBY ; 2 = IRQ_SML1_PMBUS_ALERT_N
R2P11  RES  1.00K 1% EMPTY  pkg 0402  page 170 : 1 = FM_PMBUS_ALERT_BUF_EN_N ; 2 = GND
R2P12  RES  0.0 5% EMPTY  pkg 0402  page 89 : 1 = IRQ_DIMM_SAVE_LVT3_N ; 2 = FM_ADR_SMI_GPIO_N
R2P13  RES  4.75K 1% CHIP  pkg 0402  page 170 : 1 = P3V3_STBY ; 2 = FM_PMBUS_ALERT_BUF_EN_N
R2P14  RES  0.0 5% CHIP  pkg 0402  page 185 : 1 = FM_M2_DET_LVC3 ; 2 = FM_SSATA_PCIE_M2_SEL
R2P15  RES  10.0K 1% CHIP  pkg 0402  page 185 : 1 = P3V3 ; 2 = FM_M2_SSD_PEDET
R2P16  RES  10.0K 1% CHIP  pkg 0402  page 185 : 1 = P3V3_STBY ; 2 = FM_M2_DET_LVC3
R2P17  RES  4.75K 1% CHIP  pkg 0402  page 134 : 1 = P3V3_STBY ; 2 = FM_PCH_BMC_THERMTRIP_N
R2P18  RES  10.0K 1% CHIP  pkg 0402  page 196 : 1 = P3V3_STBY ; 2 = PWRGD_P5V_N
R2P19  RES  10.0K 1% CHIP  pkg 0402  page 135 : 1 = P3V3_STBY ; 2 = FM_DIS_ADR_DLY
R2P20  RES  100.0 1% CHIP  pkg 0402  page 196 : 1 = PWRGD_P5V_R ; 2 = PWRGD_P5V
R2P21  RES  10.0K 1% CHIP  pkg 0402  page 196 : 1 = P3V3_STBY ; 2 = PWRGD_P5V_R
R2P22  RES  10.0K 1% CHIP  pkg 0402  page 133 : 1 = P3V3_STBY ; 2 = FM_CPU1_RC_EN
R2R1  RES  10.0K 1% CHIP  pkg 0402  page 192 : 1 = P3V3_STBY ; 2 = PU_RST_PERST_BIT0
R2R2  RES  33.2 1% CHIP  pkg 0402  page 190 : 1 = RST_RSMRST_R_N ; 2 = RST_RSMRST_N
R2R3  RES  10.0K 1% CHIP  pkg 0402  page 192 : 1 = P3V3_STBY ; 2 = FM_PLD_DEBUG_MODE_N
R2R4  RES  0.0 5% CHIP  pkg 0402  page 191 : 1 = FM_ADR_SMI_GPIO_R_N ; 2 = FM_ADR_SMI_GPIO_N
R2R5  RES  1.00K 1% CHIP  pkg 0402  page 133 : 1 = P3V3_STBY ; 2 = FM_PCH_PLD_DATA
R2R6  RES  51 5.0% CHIP  pkg 0402  page 191 : 1 = SGPIO_BMC_DIN_R ; 2 = SGPIO_BMC_DIN
R2R7  RES  4.75K 1% CHIP  pkg 0402  page 191 : 1 = P3V3_STBY ; 2 = FM_FORCE_ADR_N
R2R8  887R2F-L-GP  1%  pkg SMD-RG  page 187 : 1 = FM_MEZZB_PRSNT1_N ; 2 = GND
R2R9  RES  200.0 1% CHIP  pkg 0402  page 157 : 1 = FP_NMI_BTN_OUT_R_N ; 2 = FP_NMI_BTN_OUT_N
R2R10  RES  33.2 1% CHIP  pkg 0402  page 157 : 1 = FP_NMI_BTN_R_N ; 2 = FP_NMI_BTN_N
R2R11  RES  1.00K 1% EMPTY  pkg 0402  page 125 : 1 = SPI_PCH_IO2 ; 2 = GND
R2R12  RES  0.0 5% CHIP  pkg 0402  page 154 : 1 = SPI_PCH_IO2 ; 2 = SPI_PCH_IO2_R1
R2T1  RES  1.00K 1% EMPTY  pkg 0402  page 125 : 1 = SPI_PCH_IO3 ; 2 = GND
R2T2  RES  0.0 5% CHIP  pkg 0402  page 154 : 1 = SPI_PCH_IO3 ; 2 = SPI_PCH_IO3_R1
R2T3  RES  4.75K 1% CHIP  pkg 0402  page 170 : 1 = P3V3_STBY ; 2 = FM_FAST_PROCHOT_EN_N
R2T4  RES  1.0K 0.1% CHIP  pkg 0402  page 240 : 1 = P3V3_STBY ; 2 = GND
R2T5  RES  1.00K 1% CHIP  pkg 0402  page 157 : 1 = P3V3_STBY ; 2 = H_CPU0_FAST_WAKE
R2T6  RES  4.75K 1% CHIP  pkg 0402  page 154 : 1 = P3V3_STBY ; 2 = FM_BACKUP_BIOS_SEL_N
R2T7  RES  1.00K 1% CHIP  pkg 0402  page 157 : 1 = P3V3_STBY ; 2 = H_CPU0_FAST_WAKE_LVT3_N
R2T8  RES  10.0K 1% CHIP  pkg 0402  page 154 : 1 = P3V3_STBY ; 2 = SPI_SWITCH_CS0_N
R2T9  RES  75 1.0% CHIP  pkg 0402  page 154 : 1 = SPI_CS0_SECONDARY_N ; 2 = SPI_CS0_SECONDARY_R_N
R2T11  RES  4.75K 1% CHIP  pkg 0402  page 154 : 1 = P3V3_STBY ; 2 = FM_DUAL_BIOS_SEL_N
R2T13  RES  200.0 1% CHIP  pkg 0402  page 154 : 1 = SPI_CS0_PRIMARY_N ; 2 = SPI_CS0_PRIMARY_R_N
R2T16  RES  75 1.0% CHIP  pkg 0402  page 93 : 1 = H_CPU_ERR0_GTL_R_N ; 2 = H_CPU_ERR0_GTL_N
R2T17  RES  0.0 5% CHIP  pkg 0402  page 93 : 1 = H_CPU0_ERR0_G_N ; 2 = H_CPU_ERR0_GTL_R_N
R2T18  RES  49.9 1% CHIP  pkg 0402  page 156 : 1 = RST_BMC_SYSRST_BTN_OUT_B_R_N ; 2 = RST_BMC_SYSRST_BTN_OUT_B_N
R2T19  RES  200.0 1% CHIP  pkg 0402  page 93 : 1 = PVCCIO_CPU0 ; 2 = H_CPU_ERR0_GTL_R_N
R2T20  RES  0.0 5% CHIP  pkg 0402  page 93 : 1 = H_CPU1_ERR0_G_N ; 2 = H_CPU_ERR0_GTL_R_N
R2T21  RES  2.2 1.0% CHIP  pkg 0603  page 101 : 1 = P3V3_STBY_MNG ; 2 = P3V3_STBY_MNG_CPU
R2T22  RES  10.0K 1% CHIP  pkg 0402  page 156 : 1 = P3V3_STBY ; 2 = RST_BMC_SYSRST_BTN_OUT_B_R_N
R2T23  RES  2.2 1.0% CHIP  pkg 0603  page 101 : 1 = P3V3_STBY_MNG ; 2 = P3V3_STBY_MNG_RGMII
R2T25  RES  1.00K 1% CHIP  pkg 0402  page 101 : 1 = PD_CKMNG_OE ; 2 = GND
R2T26  RES  200.0 1% CHIP  pkg 0402  page 93 : 1 = PVCCIO_CPU0 ; 2 = H_CPU_ERR1_GTL_R_N
R2T27  RES  0.0 5% CHIP  pkg 0402  page 93 : 1 = H_CPU1_ERR1_G_N ; 2 = H_CPU_ERR1_GTL_R_N
R2T28  RES  33.2 1% CHIP  pkg 0402  page 156 : 1 = FM_PCH_PWRBTN_R_N ; 2 = FM_PCH_PWRBTN_N
R2T29  RES  2.21K 1% CHIP  pkg 0402  page 157 : 1 = P3V3_STBY ; 2 = IRQ_OOB_MGMT_RISER_ALERT_N
R2T30  RES  33.2 1% CHIP  pkg 0402  page 93 : 1 = FM_CPU_ERR0_LVT3_K_N ; 2 = FM_CPU_ERR0_LVT3_N
R2T31  RES  75 1.0% CHIP  pkg 0402  page 93 : 1 = H_CPU_ERR1_GTL_R_N ; 2 = H_CPU_ERR1_GTL_N
R2T32  RES  0.0 5% CHIP  pkg 0402  page 93 : 1 = H_CPU0_ERR1_G_N ; 2 = H_CPU_ERR1_GTL_R_N
R2T33  RES  33.2 1% CHIP  pkg 0402  page 93 : 1 = FM_CPU_ERR1_LVT3_K_N ; 2 = FM_CPU_ERR1_LVT3_N
R2T34  RES  4.75K 1% CHIP  pkg 0402  page 156 : 1 = P3V3_STBY ; 2 = FM_BMC_PWRBTN_OUT_N
R2T35  RES  4.75K 1% CHIP  pkg 0402  page 156 : 1 = P3V3_STBY ; 2 = RST_BMC_SYSRST_BTN_OUT_N
R2T36  374R2F-1-GP  1%  pkg SMD-RG  page 93 : 1 = P3V3 ; 2 = P0V7_GTL2104_5_VREF
R2T37  RES  200.0 1% CHIP  pkg 0402  page 92 : 1 = PVCCIO_CPU0 ; 2 = H_CPU_ERR2_G_R_N
R2T38  RES  33.2 1% CHIP  pkg 0402  page 93 : 1 = FM_CPU0_PROCHOT_LVT3_K_N ; 2 = FM_CPU0_PROCHOT_LVT3_N
R2T39  RES  100.0 1% CHIP  pkg 0402  page 93 : 1 = P0V7_GTL2104_5_VREF ; 2 = GND
R2T40  RES  0.0 5% CHIP  pkg 0402  page 92 : 1 = H_CPU0_ERR2_G_N ; 2 = H_CPU_ERR2_G_R_N
R2T41  RES  22.1 1.0% CHIP  pkg 0402  page 145 : 1 = IRQ_FORCE_NM_THROTTLE_N ; 2 = FM_BMC_SYS_THROTTLE_R_N
R2T42  RES  22.1 1.0% CHIP  pkg 0402  page 101 : 1 = CLK_50M_CKMNG_OCP_R ; 2 = CLK_50M_CKMNG_OCP
R2T43  RES  75 1.0% CHIP  pkg 0402  page 92 : 1 = H_CPU_ERR2_G_R_N ; 2 = H_CPU_ERR2_GTL_N
R2T44  RES  0.0 5% CHIP  pkg 0402  page 92 : 1 = H_CPU1_ERR2_G_N ; 2 = H_CPU_ERR2_G_R_N
R2T46  RES  22.1 1.0% CHIP  pkg 0402  page 101 : 1 = CLK_50M_CKMNG_BMC_1_R ; 2 = CLK_50M_CKMNG_BMC_1
R2T47  RES  33.2 1% CHIP  pkg 0402  page 101 : 1 = CLK_25M_CPLD_R ; 2 = CLK_25M_CPLD
R2T49  RES  20.0 1% CHIP  pkg 0402  page 159 : 1 = SMB_BMC_PMBUS_STBY_LVC3_SDA_R ; 2 = SMB_BMC_PMBUS_STBY_LVC3_SDA
R2T50  RES  1.00K 1% CHIP  pkg 0402  page 93 : 1 = PD_GTL2104_4_DIR ; 2 = GND
R2T52  RES  2.2 1.0% CHIP  pkg 0603  page 101 : 1 = P3V3_STBY_MNG ; 2 = P3V3_STBY_MNG_RMII
R2T53  RES  665 1.0% CHIP  pkg 0402  page 138 : 1 = P3V3_STBY ; 2 = SMB_BMC_PMBUS_STBY_LVC3_SDA
R2T54  RES  665 1.0% CHIP  pkg 0402  page 138 : 1 = P3V3_STBY ; 2 = SMB_BMC_PMBUS_STBY_LVC3_SCL
R2T57  RES  0.0 5% EMPTY  pkg 0402  page 93 : 1 = H_CPU_ERR0_PCH_N ; 2 = H_CPU_ERR0_GTL_R_N
R2T58  RES  0.0 5% EMPTY  pkg 0402  page 93 : 1 = H_CPU_ERR0_PCH_N ; 2 = FM_CPU_ERR0_LVT3_K_N
R2T59  RES  0.0 5% EMPTY  pkg 0402  page 93 : 1 = H_CPU0_PROCHOT_G_N ; 2 = H_CPU0_PROCHOT_G_PCH_N
R2T60  RES  0.0 5% CHIP  pkg 0402  page 93 : 1 = H_CPU0_PROCHOT_G_N ; 2 = H_CPU0_PROCHOT_G_R_N
R2T61  RES  0.0 5% EMPTY  pkg 0402  page 93 : 1 = H_CPU_ERR1_PCH_N ; 2 = H_CPU_ERR1_GTL_R_N
R2T62  RES  0.0 5% EMPTY  pkg 0402  page 93 : 1 = H_CPU_ERR1_PCH_N ; 2 = FM_CPU_ERR1_LVT3_K_N
